# BASEBOARD_FAB2 (Tioga Pass) — schematic netlist excerpt (pin names and nets, part order shuffled) for the footprints in the layout excerpt that follows; sources: Cadence DE-HDL packaged netlist, KiCad conversion of Wiwynn_Tioga_Pass_MB.brd

R3P8  RES  1.00K 1% CHIP  pkg 0402  page 133 : A = P1V05_PCH_STBY ; B = FM_PRSNT_2_6_N
C4R2  CAP_A  0.1UF 16V 10% X7R  pkg 0402V  page 113 : A = JTAG_MCP_CPU0_TDI_R ; B = GND
C3N29  CAP_A  0.1UF 16V 10% X7R  pkg 0402V  page 130 : A = A_PVCCRTC_EXT_CAP ; B = GND

(kicad_pcb
	(version 20260206)
	(generator "pcbnew")
	(generator_version "10.0")
	(general
		(thickness 1.6)
		(legacy_teardrops no)
	)
	(paper "A4")
	(title_block
		(title "Wiwynn_Tioga_Pass_MB.brd")
		(comment 1 "Tioga Pass / footprints 3640-3642 of 4770")
	)
	(layers
		(0 "F.Cu" signal "TOP")
		(4 "In1.Cu" signal "L2GND")
		(6 "In2.Cu" signal "L3")
		(8 "In3.Cu" signal "L4GND")
		(10 "In4.Cu" signal "L5")
		(12 "In5.Cu" signal "L6GND")
		(14 "In6.Cu" signal "L7VCC")
		(16 "In7.Cu" signal "L8VCC")
		(18 "In8.Cu" signal "L9GND")
		(20 "In9.Cu" signal "L10")
		(22 "In10.Cu" signal "L11GND")
		(24 "In11.Cu" signal "L12")
		(26 "In12.Cu" signal "L13GND")
		(2 "B.Cu" signal "BOTTOM")
		(9 "F.Adhes" user "F.Adhesive")
		(11 "B.Adhes" user "B.Adhesive")
		(13 "F.Paste" user "Package Geometry/Pastemask Top")
		(15 "B.Paste" user "Package Geometry/Pastemask Bottom")
		(5 "F.SilkS" user "Ref Des/Silkscreen Top")
		(7 "B.SilkS" user "Ref Des/Silkscreen Bottom")
		(1 "F.Mask" user "Board Geometry/Soldermask Top")
		(3 "B.Mask" user "Board Geometry/Soldermask Bottom")
		(17 "Dwgs.User" user "User.Drawings")
		(19 "Cmts.User" user "User.Comments")
		(21 "Eco1.User" user "User.Eco1")
		(23 "Eco2.User" user "User.Eco2")
		(25 "Edge.Cuts" user "Board Geometry/Outline")
		(27 "Margin" user)
		(31 "F.CrtYd" user "Package Geometry/Place Bound Top")
		(29 "B.CrtYd" user "Package Geometry/Place Bound Bottom")
		(35 "F.Fab" user "Ref Des/Assembly Top")
		(33 "B.Fab" user "Ref Des/Assembly Bottom")
	)
	(footprint ""
		(layer "B.Cu")
		(at 372.4275 -93.853 90)
		(property "Reference" "R3P8"
			(at 0 0 90)
			(layer "B.SilkS")
			(hide yes)
			(effects
				(font
					(size 1.27 1.27)
				)
				(justify mirror)
			)
		)
		(property "Value" ""
			(at 0 0 90)
			(layer "B.Fab")
			(effects
				(font
					(size 1.27 1.27)
				)
				(justify mirror)
			)
		)
		(duplicate_pad_numbers_are_jumpers no)
		(fp_poly
			(pts
				(xy 0.2794 -0.1016) (xy -0.2794 -0.1016) (xy -0.2794 0.9906) (xy 0.2794 0.9906)
			)
			(stroke
				(width 0)
				(type default)
			)
			(fill no)
			(layer "B.CrtYd")
		)
		(fp_line
			(start 0.2794 -0.1016)
			(end 0.2794 0.9906)
			(stroke
				(width 0.1)
				(type default)
			)
			(layer "B.Fab")
		)
		(fp_line
			(start -0.2794 -0.1016)
			(end 0.2794 -0.1016)
			(stroke
				(width 0.1)
				(type default)
			)
			(layer "B.Fab")
		)
		(fp_line
			(start 0.2794 0.9906)
			(end -0.2794 0.9906)
			(stroke
				(width 0.1)
				(type default)
			)
			(layer "B.Fab")
		)
		(fp_line
			(start -0.2794 0.9906)
			(end -0.2794 -0.1016)
			(stroke
				(width 0.1)
				(type default)
			)
			(layer "B.Fab")
		)
		(pad "1" smd rect
			(at 0 0 270)
			(size 0.508 0.508)
			(layers "B.Cu" "B.Mask" "B.Paste")
			(net "P1V05_PCH_STBY")
		)
		(pad "2" smd rect
			(at 0 0.889 270)
			(size 0.508 0.508)
			(layers "B.Cu" "B.Mask" "B.Paste")
			(net "FM_PRSNT_2_6_N")
		)
		(zone
			(layer "B.Cu")
			(hatch none 0.5)
			(connect_pads
				(clearance 0)
			)
			(min_thickness 0.25)
			(keepout
				(tracks allowed)
				(vias not_allowed)
				(pads allowed)
				(copperpour not_allowed)
				(footprints allowed)
			)
			(placement
				(enabled no)
				(sheetname "")
			)
			(fill
				(thermal_gap 0.5)
				(thermal_bridge_width 0.5)
				(island_removal_mode 0)
			)
			(polygon
				(pts
					(xy 372.6815 -94.107) (xy 372.6815 -93.599) (xy 373.0625 -93.599) (xy 373.0625 -94.107)
				)
			)
		)
		(zone
			(layer "B.Cu")
			(hatch none 0.5)
			(connect_pads
				(clearance 0)
			)
			(min_thickness 0.25)
			(keepout
				(tracks not_allowed)
				(vias allowed)
				(pads allowed)
				(copperpour not_allowed)
				(footprints allowed)
			)
			(placement
				(enabled no)
				(sheetname "")
			)
			(fill
				(thermal_gap 0.5)
				(thermal_bridge_width 0.5)
				(island_removal_mode 0)
			)
			(polygon
				(pts
					(xy 373.0625 -94.107) (xy 373.0625 -93.599) (xy 372.6815 -93.599) (xy 372.6815 -94.107)
				)
			)
		)
	)
	(footprint ""
		(layer "B.Cu")
		(at 328.803 -55.626 90)
		(property "Reference" "C4R2"
			(at 0 0 90)
			(layer "B.SilkS")
			(hide yes)
			(effects
				(font
					(size 1.27 1.27)
				)
				(justify mirror)
			)
		)
		(property "Value" ""
			(at 0 0 90)
			(layer "B.Fab")
			(effects
				(font
					(size 1.27 1.27)
				)
				(justify mirror)
			)
		)
		(duplicate_pad_numbers_are_jumpers no)
		(fp_poly
			(pts
				(xy -0.3048 -0.1016) (xy -0.3048 0.9906) (xy 0.3048 0.9906) (xy 0.3048 -0.1016)
			)
			(stroke
				(width 0)
				(type default)
			)
			(fill no)
			(layer "B.CrtYd")
		)
		(fp_line
			(start 0.3048 -0.1016)
			(end 0.3048 0.9906)
			(stroke
				(width 0.1)
				(type default)
			)
			(layer "B.Fab")
		)
		(fp_line
			(start -0.3048 -0.1016)
			(end 0.3048 -0.1016)
			(stroke
				(width 0.1)
				(type default)
			)
			(layer "B.Fab")
		)
		(fp_line
			(start 0.3048 0.9906)
			(end -0.3048 0.9906)
			(stroke
				(width 0.1)
				(type default)
			)
			(layer "B.Fab")
		)
		(fp_line
			(start -0.3048 0.9906)
			(end -0.3048 -0.1016)
			(stroke
				(width 0.1)
				(type default)
			)
			(layer "B.Fab")
		)
		(pad "1" smd rect
			(at 0 0 270)
			(size 0.508 0.508)
			(layers "B.Cu" "B.Mask" "B.Paste")
			(net "JTAG_MCP_CPU0_TDI_R")
		)
		(pad "2" smd rect
			(at 0 0.889 270)
			(size 0.508 0.508)
			(layers "B.Cu" "B.Mask" "B.Paste")
			(net "GND")
		)
		(zone
			(layer "B.Cu")
			(hatch none 0.5)
			(connect_pads
				(clearance 0)
			)
			(min_thickness 0.25)
			(keepout
				(tracks allowed)
				(vias not_allowed)
				(pads allowed)
				(copperpour not_allowed)
				(footprints allowed)
			)
			(placement
				(enabled no)
				(sheetname "")
			)
			(fill
				(thermal_gap 0.5)
				(thermal_bridge_width 0.5)
				(island_removal_mode 0)
			)
			(polygon
				(pts
					(xy 329.057 -55.88) (xy 329.057 -55.372) (xy 329.438 -55.372) (xy 329.438 -55.88)
				)
			)
		)
		(zone
			(layer "B.Cu")
			(hatch none 0.5)
			(connect_pads
				(clearance 0)
			)
			(min_thickness 0.25)
			(keepout
				(tracks not_allowed)
				(vias allowed)
				(pads allowed)
				(copperpour not_allowed)
				(footprints allowed)
			)
			(placement
				(enabled no)
				(sheetname "")
			)
			(fill
				(thermal_gap 0.5)
				(thermal_bridge_width 0.5)
				(island_removal_mode 0)
			)
			(polygon
				(pts
					(xy 329.438 -55.88) (xy 329.438 -55.372) (xy 329.057 -55.372) (xy 329.057 -55.88)
				)
			)
		)
	)
	(footprint ""
		(layer "B.Cu")
		(at 385.6228 -102.489 -90)
		(property "Reference" "C3N29"
			(at 0 0 90)
			(layer "B.SilkS")
			(hide yes)
			(effects
				(font
					(size 1.27 1.27)
				)
				(justify mirror)
			)
		)
		(property "Value" ""
			(at 0 0 90)
			(layer "B.Fab")
			(effects
				(font
					(size 1.27 1.27)
				)
				(justify mirror)
			)
		)
		(duplicate_pad_numbers_are_jumpers no)
		(fp_rect
			(start 0.2794 0.9144)
			(end -0.2794 -0.1143)
			(stroke
				(width 0)
				(type default)
			)
			(fill no)
			(layer "B.CrtYd")
		)
		(fp_line
			(start -0.2794 0.9144)
			(end 0.2794 0.9144)
			(stroke
				(width 0.1)
				(type default)
			)
			(layer "B.Fab")
		)
		(fp_line
			(start 0.2794 0.9144)
			(end 0.2794 -0.1143)
			(stroke
				(width 0.1)
				(type default)
			)
			(layer "B.Fab")
		)
		(fp_line
			(start -0.2794 -0.1143)
			(end -0.2794 0.9144)
			(stroke
				(width 0.1)
				(type default)
			)
			(layer "B.Fab")
		)
		(fp_line
			(start 0.2794 -0.1143)
			(end -0.2794 -0.1143)
			(stroke
				(width 0.1)
				(type default)
			)
			(layer "B.Fab")
		)
		(pad "1" smd custom
			(at 0 0 180)
			(size 0.10414 0.10414)
			(layers "B.Cu" "B.Mask" "B.Paste")
			(net "A_PVCCRTC_EXT_CAP")
			(options
				(clearance outline)
				(anchor circle)
			)
			(primitives
				(gr_poly
					(pts
						(xy -0.20828 -0.08636) (xy -0.20828 0.08636) (xy -0.08636 0.20828) (xy 0.086614 0.20828) (xy 0.20828 0.086614)
						(xy 0.20828 -0.08636) (xy 0.08636 -0.20828) (xy -0.08636 -0.20828)
					)
					(width 0)
					(fill yes)
				)
			)
		)
		(pad "2" smd custom
			(at 0 0.8001 180)
			(size 0.10414 0.10414)
			(layers "B.Cu" "B.Mask" "B.Paste")
			(net "GND")
			(options
				(clearance outline)
				(anchor circle)
			)
			(primitives
				(gr_poly
					(pts
						(xy -0.20828 -0.08636) (xy -0.20828 0.08636) (xy -0.08636 0.20828) (xy 0.086614 0.20828) (xy 0.20828 0.086614)
						(xy 0.20828 -0.08636) (xy 0.08636 -0.20828) (xy -0.08636 -0.20828)
					)
					(width 0)
					(fill yes)
				)
			)
		)
		(zone
			(layer "B.Cu")
			(hatch none 0.5)
			(connect_pads
				(clearance 0)
			)
			(min_thickness 0.25)
			(keepout
				(tracks not_allowed)
				(vias allowed)
				(pads allowed)
				(copperpour not_allowed)
				(footprints allowed)
			)
			(placement
				(enabled no)
				(sheetname "")
			)
			(fill
				(thermal_gap 0.5)
				(thermal_bridge_width 0.5)
				(island_removal_mode 0)
			)
			(polygon
				(pts
					(xy 385.41325 -102.40137) (xy 385.03225 -102.40137) (xy 385.03225 -102.57663) (xy 385.41325 -102.576884)
				)
			)
		)
		(zone
			(layer "B.Cu")
			(hatch none 0.5)
			(connect_pads
				(clearance 0)
			)
			(min_thickness 0.25)
			(keepout
				(tracks allowed)
				(vias not_allowed)
				(pads allowed)
				(copperpour not_allowed)
				(footprints allowed)
			)
			(placement
				(enabled no)
				(sheetname "")
			)
			(fill
				(thermal_gap 0.5)
				(thermal_bridge_width 0.5)
				(island_removal_mode 0)
			)
			(polygon
				(pts
					(xy 385.41325 -102.40137) (xy 385.03225 -102.40137) (xy 385.03225 -102.57663) (xy 385.41325 -102.576884)
				)
			)
		)
	)
)
